# T6G (Grand Teton) — schematic netlist excerpt (pin names and nets, part order shuffled) for the footprints in the layout excerpt that follows; sources: Cadence DE-HDL packaged netlist, KiCad conversion of 04192023_DAF0TMB3IC0_F0TG_MB_C_brd_V02_OCP.brd

PC6010  Q_CAP  1UF 25V 10% X6S  pkg C0402  page 269 : A = SW_P12V_AUX_P1V8_AUX_FLT ; B = GND
PD116  SCHOTTKY_AC  B340A-13-F IC  pkg D2010XF  page 152 : A = GND ; C = P12V_SCM_R
PL34  Q_INDUCTOR  0.22UH/33A IND  pkg SMLF  page 216 : \1\ = GND ; \2\ = IND_SOC_P1_CPL0

(kicad_pcb
	(version 20260206)
	(generator "pcbnew")
	(generator_version "10.0")
	(general
		(thickness 1.6)
		(legacy_teardrops no)
	)
	(paper "A4")
	(title_block
		(title "04192023_DAF0TMB3IC0_F0TG_MB_C_brd_V02_OCP.brd")
		(comment 1 "Grand Teton / footprints 4788-4790 of 8354")
	)
	(layers
		(0 "F.Cu" signal "TOP")
		(4 "In1.Cu" signal "GND")
		(6 "In2.Cu" signal "IN1")
		(8 "In3.Cu" signal "GND1")
		(10 "In4.Cu" signal "IN2")
		(12 "In5.Cu" signal "GND2")
		(14 "In6.Cu" signal "IN3")
		(16 "In7.Cu" signal "GND3")
		(18 "In8.Cu" signal "VCC")
		(20 "In9.Cu" signal "VCC1")
		(22 "In10.Cu" signal "GND4")
		(24 "In11.Cu" signal "IN4")
		(26 "In12.Cu" signal "GND5")
		(28 "In13.Cu" signal "IN5")
		(30 "In14.Cu" signal "GND6")
		(32 "In15.Cu" signal "IN6")
		(34 "In16.Cu" signal "GND7")
		(2 "B.Cu" signal "BOTTOM")
		(9 "F.Adhes" user "F.Adhesive")
		(11 "B.Adhes" user "B.Adhesive")
		(13 "F.Paste" user "Package Geometry/Pastemask Top")
		(15 "B.Paste" user "Package Geometry/Pastemask Bottom")
		(5 "F.SilkS" user "Ref Des/Silkscreen Top")
		(7 "B.SilkS" user "Ref Des/Silkscreen Bottom")
		(1 "F.Mask" user "Board Geometry/Soldermask Top")
		(3 "B.Mask" user "Board Geometry/Soldermask Bottom")
		(17 "Dwgs.User" user "User.Drawings")
		(19 "Cmts.User" user "User.Comments")
		(21 "Eco1.User" user "User.Eco1")
		(23 "Eco2.User" user "User.Eco2")
		(25 "Edge.Cuts" user "Board Geometry/Outline")
		(27 "Margin" user)
		(31 "F.CrtYd" user "Package Geometry/Place Bound Top")
		(29 "B.CrtYd" user "Package Geometry/Place Bound Bottom")
		(35 "F.Fab" user "Ref Des/Assembly Top")
		(33 "B.Fab" user "Ref Des/Assembly Bottom")
	)
	(footprint ""
		(layer "F.Cu")
		(at 191.806322 -20.126452 180)
		(property "Reference" "PD116"
			(at -2.53746 2.96545 0)
			(unlocked yes)
			(layer "F.SilkS")
			(effects
				(font
					(size 0.7874 0.5842)
					(thickness 0.1524)
				)
				(justify left)
			)
		)
		(property "Value" ""
			(at 0 0 180)
			(layer "F.Fab")
			(effects
				(font
					(size 1.27 1.27)
				)
			)
		)
		(duplicate_pad_numbers_are_jumpers no)
		(fp_line
			(start 4.107942 1.459992)
			(end -3.400044 1.459992)
			(stroke
				(width 0.1524)
				(type default)
			)
			(layer "F.SilkS")
		)
		(fp_line
			(start 4.107942 -1.459992)
			(end 4.107942 1.459992)
			(stroke
				(width 0.1524)
				(type default)
			)
			(layer "F.SilkS")
		)
		(fp_line
			(start -3.400044 1.459992)
			(end -3.400044 -1.459992)
			(stroke
				(width 0.1524)
				(type default)
			)
			(layer "F.SilkS")
		)
		(fp_line
			(start -3.400044 -1.459992)
			(end 4.107942 -1.459992)
			(stroke
				(width 0.1524)
				(type default)
			)
			(layer "F.SilkS")
		)
		(fp_rect
			(start 4.107942 -1.459992)
			(end 3.308096 1.459992)
			(stroke
				(width 0)
				(type default)
			)
			(fill yes)
			(layer "F.SilkS")
		)
		(fp_line
			(start 2.29997 1.459992)
			(end -2.29997 1.459992)
			(stroke
				(width 0.1)
				(type default)
			)
			(layer "F.Fab")
		)
		(fp_line
			(start 2.29997 -1.459992)
			(end 2.29997 1.459992)
			(stroke
				(width 0.1)
				(type default)
			)
			(layer "F.Fab")
		)
		(fp_line
			(start -2.29997 1.459992)
			(end -2.29997 -1.459992)
			(stroke
				(width 0.1)
				(type default)
			)
			(layer "F.Fab")
		)
		(fp_line
			(start -2.29997 -1.459992)
			(end 2.29997 -1.459992)
			(stroke
				(width 0.1)
				(type default)
			)
			(layer "F.Fab")
		)
		(fp_text user "-"
			(at 5.50418 1.00203 0)
			(unlocked yes)
			(layer "F.SilkS")
			(effects
				(font
					(size 1.905 1.4224)
					(thickness 0.1524)
				)
				(justify left)
			)
		)
		(fp_text user "+"
			(at -5.283962 -0.182118 180)
			(unlocked yes)
			(layer "F.SilkS")
			(effects
				(font
					(size 1.905 1.4224)
					(thickness 0.1524)
				)
				(justify left)
			)
		)
		(fp_text user "-"
			(at 5.4102 0.29845 0)
			(unlocked yes)
			(layer "F.Fab")
			(effects
				(font
					(size 1.905 1.4224)
					(thickness 0.1524)
				)
				(justify left)
			)
		)
		(fp_text user "+"
			(at -4.7752 -0.12065 180)
			(unlocked yes)
			(layer "F.Fab")
			(effects
				(font
					(size 1.905 1.4224)
					(thickness 0.1524)
				)
				(justify left)
			)
		)
		(pad "A" smd rect
			(at -1.999996 0 270)
			(size 1.7018 2.5146)
			(layers "F.Cu" "F.Mask" "F.Paste")
			(net "GND")
		)
		(pad "C" smd rect
			(at 1.999996 0 270)
			(size 1.7018 2.5146)
			(layers "F.Cu" "F.Mask" "F.Paste")
			(net "P12V_SCM_R")
		)
	)
	(footprint ""
		(layer "F.Cu")
		(at 141.233652 -79.029052 90)
		(property "Reference" "PC6010"
			(at 0 0 90)
			(layer "F.SilkS")
			(hide yes)
			(effects
				(font
					(size 1.27 1.27)
				)
			)
		)
		(property "Value" ""
			(at 0 0 90)
			(layer "F.Fab")
			(effects
				(font
					(size 1.27 1.27)
				)
			)
		)
		(duplicate_pad_numbers_are_jumpers no)
		(fp_line
			(start 0.7874 -0.4064)
			(end 0.7874 0.4064)
			(stroke
				(width 0.1524)
				(type default)
			)
			(layer "F.SilkS")
		)
		(fp_line
			(start -0.7874 -0.4064)
			(end 0.7874 -0.4064)
			(stroke
				(width 0.1524)
				(type default)
			)
			(layer "F.SilkS")
		)
		(fp_line
			(start 0.7874 0.4064)
			(end -0.7874 0.4064)
			(stroke
				(width 0.1524)
				(type default)
			)
			(layer "F.SilkS")
		)
		(fp_line
			(start -0.7874 0.4064)
			(end -0.7874 -0.4064)
			(stroke
				(width 0.1524)
				(type default)
			)
			(layer "F.SilkS")
		)
		(fp_line
			(start -0.12065 -0.305054)
			(end -0.12065 -0.2794)
			(stroke
				(width 0.1)
				(type default)
			)
			(layer "F.Fab")
		)
		(fp_line
			(start -0.67945 -0.305054)
			(end -0.12065 -0.305054)
			(stroke
				(width 0.1)
				(type default)
			)
			(layer "F.Fab")
		)
		(fp_line
			(start 0.67945 -0.3048)
			(end 0.67945 0.3048)
			(stroke
				(width 0.1)
				(type default)
			)
			(layer "F.Fab")
		)
		(fp_line
			(start 0.12065 -0.3048)
			(end 0.67945 -0.3048)
			(stroke
				(width 0.1)
				(type default)
			)
			(layer "F.Fab")
		)
		(fp_line
			(start 0.12065 -0.2794)
			(end 0.12065 -0.3048)
			(stroke
				(width 0.1)
				(type default)
			)
			(layer "F.Fab")
		)
		(fp_line
			(start -0.12065 -0.2794)
			(end 0.12065 -0.2794)
			(stroke
				(width 0.1)
				(type default)
			)
			(layer "F.Fab")
		)
		(fp_line
			(start 0.120396 0.2794)
			(end -0.12065 0.2794)
			(stroke
				(width 0.1)
				(type default)
			)
			(layer "F.Fab")
		)
		(fp_line
			(start -0.12065 0.2794)
			(end -0.12065 0.3048)
			(stroke
				(width 0.1)
				(type default)
			)
			(layer "F.Fab")
		)
		(fp_line
			(start 0.67945 0.3048)
			(end 0.120396 0.3048)
			(stroke
				(width 0.1)
				(type default)
			)
			(layer "F.Fab")
		)
		(fp_line
			(start 0.120396 0.3048)
			(end 0.120396 0.2794)
			(stroke
				(width 0.1)
				(type default)
			)
			(layer "F.Fab")
		)
		(fp_line
			(start -0.12065 0.3048)
			(end -0.67945 0.3048)
			(stroke
				(width 0.1)
				(type default)
			)
			(layer "F.Fab")
		)
		(fp_line
			(start -0.67945 0.3048)
			(end -0.67945 -0.305054)
			(stroke
				(width 0.1)
				(type default)
			)
			(layer "F.Fab")
		)
		(pad "1" smd circle
			(at -0.40005 0 90)
			(size 0 0)
			(layers "F.Cu" "F.Mask" "F.Paste")
			(net "SW_P12V_AUX_P1V8_AUX_FLT")
		)
		(pad "2" smd circle
			(at 0.40005 0 90)
			(size 0 0)
			(layers "F.Cu" "F.Mask" "F.Paste")
			(net "GND")
		)
	)
	(footprint ""
		(layer "F.Cu")
		(at 140.661898 -160.403794 90)
		(property "Reference" "PL34"
			(at 3.955796 -3.199384 0)
			(unlocked yes)
			(layer "F.SilkS")
			(effects
				(font
					(size 0.7874 0.5842)
					(thickness 0.1524)
				)
				(justify left)
			)
		)
		(property "Value" ""
			(at 0 0 90)
			(layer "F.Fab")
			(effects
				(font
					(size 1.27 1.27)
				)
			)
		)
		(duplicate_pad_numbers_are_jumpers no)
		(fp_line
			(start 3.24993 -3.24993)
			(end 3.24993 -2.2352)
			(stroke
				(width 0.1524)
				(type default)
			)
			(layer "F.SilkS")
		)
		(fp_line
			(start -3.24993 -3.24993)
			(end 3.24993 -3.24993)
			(stroke
				(width 0.1524)
				(type default)
			)
			(layer "F.SilkS")
		)
		(fp_line
			(start -3.24993 -2.2352)
			(end -3.24993 -3.24993)
			(stroke
				(width 0.1524)
				(type default)
			)
			(layer "F.SilkS")
		)
		(fp_line
			(start 3.24993 2.2352)
			(end 3.24993 3.24993)
			(stroke
				(width 0.1524)
				(type default)
			)
			(layer "F.SilkS")
		)
		(fp_line
			(start 3.24993 3.24993)
			(end -3.24993 3.24993)
			(stroke
				(width 0.1524)
				(type default)
			)
			(layer "F.SilkS")
		)
		(fp_line
			(start -3.24993 3.24993)
			(end -3.24993 2.2352)
			(stroke
				(width 0.1524)
				(type default)
			)
			(layer "F.SilkS")
		)
		(fp_line
			(start 3.24993 -3.24993)
			(end 3.24993 3.24993)
			(stroke
				(width 0.1)
				(type default)
			)
			(layer "F.Fab")
		)
		(fp_line
			(start -3.24993 -3.24993)
			(end 3.24993 -3.24993)
			(stroke
				(width 0.1)
				(type default)
			)
			(layer "F.Fab")
		)
		(fp_line
			(start 3.24993 3.24993)
			(end -3.24993 3.24993)
			(stroke
				(width 0.1)
				(type default)
			)
			(layer "F.Fab")
		)
		(fp_line
			(start -3.24993 3.24993)
			(end -3.24993 -3.24993)
			(stroke
				(width 0.1)
				(type default)
			)
			(layer "F.Fab")
		)
		(pad "1" smd rect
			(at -2.29997 0 90)
			(size 2.0066 4.2164)
			(layers "F.Cu" "F.Mask" "F.Paste")
			(net "GND")
		)
		(pad "2" smd rect
			(at 2.29997 0 90)
			(size 2.0066 4.2164)
			(layers "F.Cu" "F.Mask" "F.Paste")
			(net "IND_SOC_P1_CPL0")
		)
	)
)
